(kicad_pcb
	(version 20260206)
	(generator "pcbnew")
	(generator_version "10.0")
	(general
		(thickness 1.6)
		(legacy_teardrops no)
	)
	(paper "A4")
	(title_block
		(title "Bryce Canyon_R.DPB_16317-1_OCP.brd")
		(comment 1 "Bryce Canyon / footprints 562-569 of 2099")
	)
	(layers
		(0 "F.Cu" signal "TOP")
		(4 "In1.Cu" signal "L2GND")
		(6 "In2.Cu" signal "L3")
		(8 "In3.Cu" signal "L4VCC")
		(10 "In4.Cu" signal "L5VCC")
		(12 "In5.Cu" signal "L6")
		(14 "In6.Cu" signal "L7GND")
		(2 "B.Cu" signal "BOTTOM")
		(9 "F.Adhes" user "F.Adhesive")
		(11 "B.Adhes" user "B.Adhesive")
		(13 "F.Paste" user "Package Geometry/Pastemask Top")
		(15 "B.Paste" user "Package Geometry/Pastemask Bottom")
		(5 "F.SilkS" user "Ref Des/Silkscreen Top")
		(7 "B.SilkS" user "Ref Des/Silkscreen Bottom")
		(1 "F.Mask" user "Board Geometry/Soldermask Top")
		(3 "B.Mask" user "Board Geometry/Soldermask Bottom")
		(17 "Dwgs.User" user "User.Drawings")
		(19 "Cmts.User" user "User.Comments")
		(21 "Eco1.User" user "User.Eco1")
		(23 "Eco2.User" user "User.Eco2")
		(25 "Edge.Cuts" user "Board Geometry/Outline")
		(27 "Margin" user)
		(31 "F.CrtYd" user "Package Geometry/Place Bound Top")
		(29 "B.CrtYd" user "Package Geometry/Place Bound Bottom")
		(35 "F.Fab" user "Ref Des/Assembly Top")
		(33 "B.Fab" user "Ref Des/Assembly Bottom")
	)
	(footprint ""
		(layer "F.Cu")
		(at 52.324 -256.286 180)
		(property "Reference" "Q2"
			(at 0 0 180)
			(layer "F.SilkS")
			(hide yes)
			(effects
				(font
					(size 1.27 1.27)
				)
			)
		)
		(property "Value" "AO4406AL-GP"
			(at -3.707384 -1.5367 180)
			(unlocked yes)
			(layer "F.Fab")
			(hide yes)
			(effects
				(font
					(size 1.016 1.016)
					(thickness 0.1524)
				)
			)
		)
		(property "Device Type" "SOIC8H69"
			(at -3.707384 -3.0607 180)
			(unlocked yes)
			(layer "F.Fab")
			(hide yes)
			(effects
				(font
					(size 1.016 1.016)
					(thickness 0.1524)
				)
			)
		)
		(duplicate_pad_numbers_are_jumpers no)
		(fp_line
			(start 2.1336 1.4224)
			(end 2.1336 -1.4224)
			(stroke
				(width 0.1524)
				(type default)
			)
			(layer "F.SilkS")
		)
		(fp_line
			(start 2.1336 -1.4224)
			(end -2.7432 -1.4224)
			(stroke
				(width 0.1524)
				(type default)
			)
			(layer "F.SilkS")
		)
		(fp_line
			(start -2.1844 -0.0508)
			(end -2.7178 0.508)
			(stroke
				(width 0.1524)
				(type default)
			)
			(layer "F.SilkS")
		)
		(fp_line
			(start -2.6289 3.4417)
			(end -2.6289 1.4732)
			(stroke
				(width 0.381)
				(type default)
			)
			(layer "F.SilkS")
		)
		(fp_line
			(start -2.7178 -0.508)
			(end -2.1844 -0.0508)
			(stroke
				(width 0.1524)
				(type default)
			)
			(layer "F.SilkS")
		)
		(fp_line
			(start -2.7432 1.4224)
			(end 2.1336 1.4224)
			(stroke
				(width 0.1524)
				(type default)
			)
			(layer "F.SilkS")
		)
		(fp_line
			(start -2.7432 1.4224)
			(end -2.6416 1.4224)
			(stroke
				(width 0.1524)
				(type default)
			)
			(layer "F.SilkS")
		)
		(fp_line
			(start -2.7432 -1.4224)
			(end -2.7432 1.4224)
			(stroke
				(width 0.1524)
				(type default)
			)
			(layer "F.SilkS")
		)
		(fp_poly
			(pts
				(xy -2.2098 -1.4224) (xy -2.2098 1.4224) (xy 2.2098 1.4224) (xy 2.2098 -1.4224)
			)
			(stroke
				(width 0)
				(type default)
			)
			(fill yes)
			(layer "F.SilkS")
		)
		(fp_rect
			(start -2.450084 2.999994)
			(end 2.450084 -2.999994)
			(stroke
				(width 0)
				(type default)
			)
			(fill no)
			(layer "F.CrtYd")
		)
		(fp_poly
			(pts
				(xy -2.8194 3.6322) (xy -2.8194 -3.6322) (xy 2.8194 -3.6322) (xy 2.8194 1.18364) (xy 2.450084 1.18364)
				(xy 2.450084 -2.999994) (xy -2.450084 -2.999994) (xy -2.450084 2.999994) (xy 2.450084 2.999994)
				(xy 2.450084 1.18618) (xy 2.8194 1.18618) (xy 2.8194 3.6322)
			)
			(stroke
				(width 0)
				(type default)
			)
			(fill no)
			(layer "F.CrtYd")
		)
		(fp_rect
			(start -2.8194 3.6322)
			(end 2.8194 -3.6322)
			(stroke
				(width 0)
				(type default)
			)
			(fill no)
			(layer "F.Fab")
		)
		(pad "1" smd rect
			(at -1.905 2.54 180)
			(size 0.635 1.651)
			(layers "F.Cu" "F.Mask" "F.Paste")
			(net "P5V_HDD1")
		)
		(pad "2" smd rect
			(at -0.635 2.54 180)
			(size 0.635 1.651)
			(layers "F.Cu" "F.Mask" "F.Paste")
			(net "P5V_HDD1")
		)
		(pad "3" smd rect
			(at 0.635 2.54 180)
			(size 0.635 1.651)
			(layers "F.Cu" "F.Mask" "F.Paste")
			(net "P5V_HDD1")
		)
		(pad "4" smd rect
			(at 1.905 2.54 180)
			(size 0.635 1.651)
			(layers "F.Cu" "F.Mask" "F.Paste")
			(net "SW_HDD_P1")
		)
		(pad "5" smd rect
			(at 1.905 -2.54 180)
			(size 0.635 1.651)
			(layers "F.Cu" "F.Mask" "F.Paste")
			(net "P5V_B_1")
		)
		(pad "6" smd rect
			(at 0.635 -2.54 180)
			(size 0.635 1.651)
			(layers "F.Cu" "F.Mask" "F.Paste")
			(net "P5V_B_1")
		)
		(pad "7" smd rect
			(at -0.635 -2.54 180)
			(size 0.635 1.651)
			(layers "F.Cu" "F.Mask" "F.Paste")
			(net "P5V_B_1")
		)
		(pad "8" smd rect
			(at -1.905 -2.54 180)
			(size 0.635 1.651)
			(layers "F.Cu" "F.Mask" "F.Paste")
			(net "P5V_B_1")
		)
	)
	(footprint ""
		(layer "F.Cu")
		(at 109.347 -150.622 -90)
		(property "Reference" "C229"
			(at 0 0 270)
			(layer "F.SilkS")
			(hide yes)
			(effects
				(font
					(size 1.27 1.27)
				)
			)
		)
		(property "Value" "SC4D7U25V5KX-1-GP"
			(at -0.0762 -6.1214 270)
			(unlocked yes)
			(layer "F.Fab")
			(hide yes)
			(effects
				(font
					(size 1.016 1.016)
					(thickness 0.1524)
				)
			)
		)
		(property "Device Type" "C805H58"
			(at -0.0762 -8.1534 270)
			(unlocked yes)
			(layer "F.Fab")
			(hide yes)
			(effects
				(font
					(size 1.016 1.016)
					(thickness 0.1524)
				)
			)
		)
		(duplicate_pad_numbers_are_jumpers no)
		(fp_line
			(start 0.635 0)
			(end -0.635 0)
			(stroke
				(width 0.508)
				(type default)
			)
			(layer "F.SilkS")
		)
		(fp_rect
			(start -0.9652 1.778)
			(end 0.9652 -1.778)
			(stroke
				(width 0)
				(type default)
			)
			(fill no)
			(layer "F.CrtYd")
		)
		(fp_poly
			(pts
				(xy -0.9652 -1.778) (xy 0.9652 -1.778) (xy 0.9652 1.778) (xy -0.9652 1.778)
			)
			(stroke
				(width 0)
				(type default)
			)
			(fill no)
			(layer "F.Fab")
		)
		(pad "1" smd rect
			(at 0 -0.9652 270)
			(size 1.397 1.143)
			(layers "F.Cu" "F.Mask" "F.Paste")
			(net "P12V_HDD15")
		)
		(pad "2" smd rect
			(at 0 0.9652 270)
			(size 1.397 1.143)
			(layers "F.Cu" "F.Mask" "F.Paste")
			(net "GND")
		)
	)
	(footprint ""
		(layer "F.Cu")
		(at 175.514 -363.22 90)
		(property "Reference" "R1007"
			(at 0 0 90)
			(layer "F.SilkS")
			(hide yes)
			(effects
				(font
					(size 1.27 1.27)
				)
			)
		)
		(property "Value" "100KR2F-L1-GP"
			(at 0.064008 -3.993896 90)
			(unlocked yes)
			(layer "F.Fab")
			(hide yes)
			(effects
				(font
					(size 1.016 1.016)
					(thickness 0.1524)
				)
			)
		)
		(property "Device Type" "R402H16"
			(at 0.064008 -5.517896 90)
			(unlocked yes)
			(layer "F.Fab")
			(hide yes)
			(effects
				(font
					(size 1.016 1.016)
					(thickness 0.1524)
				)
			)
		)
		(duplicate_pad_numbers_are_jumpers no)
		(fp_line
			(start 0.508 -0.9398)
			(end -0.508 -0.9398)
			(stroke
				(width 0.1524)
				(type default)
			)
			(layer "F.SilkS")
		)
		(fp_line
			(start -0.508 -0.9398)
			(end -0.508 0.9398)
			(stroke
				(width 0.1524)
				(type default)
			)
			(layer "F.SilkS")
		)
		(fp_rect
			(start -0.508 0.9398)
			(end 0.508 -0.9398)
			(stroke
				(width 0)
				(type default)
			)
			(fill no)
			(layer "F.CrtYd")
		)
		(fp_rect
			(start -0.508 0.9398)
			(end 0.508 -0.9398)
			(stroke
				(width 0)
				(type default)
			)
			(fill no)
			(layer "F.Fab")
		)
		(pad "1" smd custom
			(at 0 -0.4445 90)
			(size 0.1397 0.1397)
			(layers "F.Cu" "F.Mask" "F.Paste")
			(net "MB0_VCAP_R")
			(options
				(clearance outline)
				(anchor circle)
			)
			(primitives
				(gr_poly
					(pts
						(arc
							(start -0.1778 -0.2794)
							(mid -0.249642 -0.249642)
							(end -0.2794 -0.1778)
						)
						(arc
							(start -0.2794 0.1778)
							(mid -0.249642 0.249642)
							(end -0.1778 0.2794)
						)
						(arc
							(start 0.1778 0.2794)
							(mid 0.249642 0.249642)
							(end 0.2794 0.1778)
						)
						(arc
							(start 0.2794 -0.1778)
							(mid 0.249642 -0.249642)
							(end 0.1778 -0.2794)
						)
					)
					(width 0)
					(fill yes)
				)
			)
		)
		(pad "2" smd custom
			(at 0 0.4445 90)
			(size 0.1397 0.1397)
			(layers "F.Cu" "F.Mask" "F.Paste")
			(net "MB0_ISTART_R")
			(options
				(clearance outline)
				(anchor circle)
			)
			(primitives
				(gr_poly
					(pts
						(arc
							(start -0.1778 -0.2794)
							(mid -0.249642 -0.249642)
							(end -0.2794 -0.1778)
						)
						(arc
							(start -0.2794 0.1778)
							(mid -0.249642 0.249642)
							(end -0.1778 0.2794)
						)
						(arc
							(start 0.1778 0.2794)
							(mid 0.249642 0.249642)
							(end 0.2794 0.1778)
						)
						(arc
							(start 0.2794 -0.1778)
							(mid 0.249642 -0.249642)
							(end 0.1778 -0.2794)
						)
					)
					(width 0)
					(fill yes)
				)
			)
		)
	)
	(footprint ""
		(layer "F.Cu")
		(at 384.8608 -146.6342)
		(property "Reference" "C297"
			(at 0 0 0)
			(layer "F.SilkS")
			(hide yes)
			(effects
				(font
					(size 1.27 1.27)
				)
			)
		)
		(property "Value" "SCD01U50V2KX-1GP"
			(at 1.1811 -2.7051 0)
			(unlocked yes)
			(layer "F.Fab")
			(hide yes)
			(effects
				(font
					(size 1.016 1.016)
					(thickness 0.1524)
				)
			)
		)
		(property "Device Type" "C402H22"
			(at 1.1811 -4.2291 0)
			(unlocked yes)
			(layer "F.Fab")
			(hide yes)
			(effects
				(font
					(size 1.016 1.016)
					(thickness 0.1524)
				)
			)
		)
		(duplicate_pad_numbers_are_jumpers no)
		(fp_rect
			(start -0.4318 0.9525)
			(end 0.4318 -0.9525)
			(stroke
				(width 0)
				(type default)
			)
			(fill no)
			(layer "F.CrtYd")
		)
		(fp_rect
			(start -0.4318 0.9525)
			(end 0.4318 -0.9525)
			(stroke
				(width 0)
				(type default)
			)
			(fill no)
			(layer "F.Fab")
		)
		(pad "1" smd custom
			(at 0 -0.4445)
			(size 0.1524 0.1524)
			(layers "F.Cu" "F.Mask" "F.Paste")
			(net "HDD_PRSNT_20")
			(options
				(clearance outline)
				(anchor circle)
			)
			(primitives
				(gr_poly
					(pts
						(arc
							(start 0.3048 -0.2032)
							(mid 0.275042 -0.275042)
							(end 0.2032 -0.3048)
						)
						(arc
							(start -0.2032 -0.3048)
							(mid -0.275042 -0.275042)
							(end -0.3048 -0.2032)
						)
						(arc
							(start -0.3048 0.2032)
							(mid -0.275042 0.275042)
							(end -0.2032 0.3048)
						)
						(arc
							(start 0.2032 0.3048)
							(mid 0.275042 0.275042)
							(end 0.3048 0.2032)
						)
					)
					(width 0)
					(fill yes)
				)
			)
		)
		(pad "2" smd custom
			(at 0 0.4445)
			(size 0.1524 0.1524)
			(layers "F.Cu" "F.Mask" "F.Paste")
			(net "GND")
			(options
				(clearance outline)
				(anchor circle)
			)
			(primitives
				(gr_poly
					(pts
						(arc
							(start 0.3048 -0.2032)
							(mid 0.275042 -0.275042)
							(end 0.2032 -0.3048)
						)
						(arc
							(start -0.2032 -0.3048)
							(mid -0.275042 -0.275042)
							(end -0.3048 -0.2032)
						)
						(arc
							(start -0.3048 0.2032)
							(mid -0.275042 0.275042)
							(end -0.2032 0.3048)
						)
						(arc
							(start 0.2032 0.3048)
							(mid 0.275042 0.275042)
							(end 0.3048 0.2032)
						)
					)
					(width 0)
					(fill yes)
				)
			)
		)
	)
	(footprint ""
		(layer "F.Cu")
		(at 172.466 -265.684 -90)
		(property "Reference" "C99"
			(at 0 0 270)
			(layer "F.SilkS")
			(hide yes)
			(effects
				(font
					(size 1.27 1.27)
				)
			)
		)
		(property "Value" "SC4D7U25V5KX-1-GP"
			(at -0.0762 -6.1214 270)
			(unlocked yes)
			(layer "F.Fab")
			(hide yes)
			(effects
				(font
					(size 1.016 1.016)
					(thickness 0.1524)
				)
			)
		)
		(property "Device Type" "C805H58"
			(at -0.0762 -8.1534 270)
			(unlocked yes)
			(layer "F.Fab")
			(hide yes)
			(effects
				(font
					(size 1.016 1.016)
					(thickness 0.1524)
				)
			)
		)
		(duplicate_pad_numbers_are_jumpers no)
		(fp_line
			(start 0.635 0)
			(end -0.635 0)
			(stroke
				(width 0.508)
				(type default)
			)
			(layer "F.SilkS")
		)
		(fp_rect
			(start -0.9652 1.778)
			(end 0.9652 -1.778)
			(stroke
				(width 0)
				(type default)
			)
			(fill no)
			(layer "F.CrtYd")
		)
		(fp_poly
			(pts
				(xy -0.9652 -1.778) (xy 0.9652 -1.778) (xy 0.9652 1.778) (xy -0.9652 1.778)
			)
			(stroke
				(width 0)
				(type default)
			)
			(fill no)
			(layer "F.Fab")
		)
		(pad "1" smd rect
			(at 0 -0.9652 270)
			(size 1.397 1.143)
			(layers "F.Cu" "F.Mask" "F.Paste")
			(net "P12V_HDD5")
		)
		(pad "2" smd rect
			(at 0 0.9652 270)
			(size 1.397 1.143)
			(layers "F.Cu" "F.Mask" "F.Paste")
			(net "GND")
		)
	)
	(footprint ""
		(layer "F.Cu")
		(at 151.33447 -217.642186 -90)
		(property "Reference" "R210"
			(at 0 0 270)
			(layer "F.SilkS")
			(hide yes)
			(effects
				(font
					(size 1.27 1.27)
				)
			)
		)
		(property "Value" "4K7R2F-GP"
			(at 0.064008 -3.993896 270)
			(unlocked yes)
			(layer "F.Fab")
			(hide yes)
			(effects
				(font
					(size 1.016 1.016)
					(thickness 0.1524)
				)
			)
		)
		(property "Device Type" "R402H16"
			(at 0.064008 -5.517896 270)
			(unlocked yes)
			(layer "F.Fab")
			(hide yes)
			(effects
				(font
					(size 1.016 1.016)
					(thickness 0.1524)
				)
			)
		)
		(duplicate_pad_numbers_are_jumpers no)
		(fp_line
			(start -0.508 -0.9398)
			(end -0.508 0.9398)
			(stroke
				(width 0.1524)
				(type default)
			)
			(layer "F.SilkS")
		)
		(fp_line
			(start 0.508 -0.9398)
			(end -0.508 -0.9398)
			(stroke
				(width 0.1524)
				(type default)
			)
			(layer "F.SilkS")
		)
		(fp_rect
			(start -0.508 0.9398)
			(end 0.508 -0.9398)
			(stroke
				(width 0)
				(type default)
			)
			(fill no)
			(layer "F.CrtYd")
		)
		(fp_rect
			(start -0.508 0.9398)
			(end 0.508 -0.9398)
			(stroke
				(width 0)
				(type default)
			)
			(fill no)
			(layer "F.Fab")
		)
		(pad "1" smd custom
			(at 0 -0.4445 270)
			(size 0.1397 0.1397)
			(layers "F.Cu" "F.Mask" "F.Paste")
			(net "DRIVE_B_4_FLT_LED")
			(options
				(clearance outline)
				(anchor circle)
			)
			(primitives
				(gr_poly
					(pts
						(arc
							(start -0.1778 -0.2794)
							(mid -0.249642 -0.249642)
							(end -0.2794 -0.1778)
						)
						(arc
							(start -0.2794 0.1778)
							(mid -0.249642 0.249642)
							(end -0.1778 0.2794)
						)
						(arc
							(start 0.1778 0.2794)
							(mid 0.249642 0.249642)
							(end 0.2794 0.1778)
						)
						(arc
							(start 0.2794 -0.1778)
							(mid 0.249642 -0.249642)
							(end 0.1778 -0.2794)
						)
					)
					(width 0)
					(fill yes)
				)
			)
		)
		(pad "2" smd custom
			(at 0 0.4445 270)
			(size 0.1397 0.1397)
			(layers "F.Cu" "F.Mask" "F.Paste")
			(net "GND")
			(options
				(clearance outline)
				(anchor circle)
			)
			(primitives
				(gr_poly
					(pts
						(arc
							(start -0.1778 -0.2794)
							(mid -0.249642 -0.249642)
							(end -0.2794 -0.1778)
						)
						(arc
							(start -0.2794 0.1778)
							(mid -0.249642 0.249642)
							(end -0.1778 0.2794)
						)
						(arc
							(start 0.1778 0.2794)
							(mid 0.249642 0.249642)
							(end 0.2794 0.1778)
						)
						(arc
							(start 0.2794 -0.1778)
							(mid 0.249642 -0.249642)
							(end 0.1778 -0.2794)
						)
					)
					(width 0)
					(fill yes)
				)
			)
		)
	)
	(footprint ""
		(layer "F.Cu")
		(at 14.859 -131.572 90)
		(property "Reference" "R360"
			(at 0 0 90)
			(layer "F.SilkS")
			(hide yes)
			(effects
				(font
					(size 1.27 1.27)
				)
			)
		)
		(property "Value" "4K7R2J-2-GP"
			(at 0.064008 -3.993896 90)
			(unlocked yes)
			(layer "F.Fab")
			(hide yes)
			(effects
				(font
					(size 1.016 1.016)
					(thickness 0.1524)
				)
			)
		)
		(property "Device Type" "R402H16"
			(at 0.064008 -5.517896 90)
			(unlocked yes)
			(layer "F.Fab")
			(hide yes)
			(effects
				(font
					(size 1.016 1.016)
					(thickness 0.1524)
				)
			)
		)
		(duplicate_pad_numbers_are_jumpers no)
		(fp_line
			(start 0.508 -0.9398)
			(end -0.508 -0.9398)
			(stroke
				(width 0.1524)
				(type default)
			)
			(layer "F.SilkS")
		)
		(fp_line
			(start -0.508 -0.9398)
			(end -0.508 0.9398)
			(stroke
				(width 0.1524)
				(type default)
			)
			(layer "F.SilkS")
		)
		(fp_rect
			(start -0.508 0.9398)
			(end 0.508 -0.9398)
			(stroke
				(width 0)
				(type default)
			)
			(fill no)
			(layer "F.CrtYd")
		)
		(fp_rect
			(start -0.508 0.9398)
			(end 0.508 -0.9398)
			(stroke
				(width 0)
				(type default)
			)
			(fill no)
			(layer "F.Fab")
		)
		(pad "1" smd custom
			(at 0 -0.4445 90)
			(size 0.1397 0.1397)
			(layers "F.Cu" "F.Mask" "F.Paste")
			(net "P12V_B")
			(options
				(clearance outline)
				(anchor circle)
			)
			(primitives
				(gr_poly
					(pts
						(arc
							(start -0.1778 -0.2794)
							(mid -0.249642 -0.249642)
							(end -0.2794 -0.1778)
						)
						(arc
							(start -0.2794 0.1778)
							(mid -0.249642 0.249642)
							(end -0.1778 0.2794)
						)
						(arc
							(start 0.1778 0.2794)
							(mid 0.249642 0.249642)
							(end 0.2794 0.1778)
						)
						(arc
							(start 0.2794 -0.1778)
							(mid 0.249642 -0.249642)
							(end 0.1778 -0.2794)
						)
					)
					(width 0)
					(fill yes)
				)
			)
		)
		(pad "2" smd custom
			(at 0 0.4445 90)
			(size 0.1397 0.1397)
			(layers "F.Cu" "F.Mask" "F.Paste")
			(net "SW_HDD_R12")
			(options
				(clearance outline)
				(anchor circle)
			)
			(primitives
				(gr_poly
					(pts
						(arc
							(start -0.1778 -0.2794)
							(mid -0.249642 -0.249642)
							(end -0.2794 -0.1778)
						)
						(arc
							(start -0.2794 0.1778)
							(mid -0.249642 0.249642)
							(end -0.1778 0.2794)
						)
						(arc
							(start 0.1778 0.2794)
							(mid 0.249642 0.249642)
							(end 0.2794 0.1778)
						)
						(arc
							(start 0.2794 -0.1778)
							(mid 0.249642 -0.249642)
							(end 0.1778 -0.2794)
						)
					)
					(width 0)
					(fill yes)
				)
			)
		)
	)
	(footprint ""
		(layer "F.Cu")
		(at 87.376 -160.401 180)
		(property "Reference" "C219"
			(at 0 0 180)
			(layer "F.SilkS")
			(hide yes)
			(effects
				(font
					(size 1.27 1.27)
				)
			)
		)
		(property "Value" "SC1U25V3KX-GP"
			(at 0 -2.8194 180)
			(unlocked yes)
			(layer "F.Fab")
			(hide yes)
			(effects
				(font
					(size 1.016 1.016)
					(thickness 0.1524)
				)
			)
		)
		(property "Device Type" "C603H36"
			(at 0 -4.3434 180)
			(unlocked yes)
			(layer "F.Fab")
			(hide yes)
			(effects
				(font
					(size 1.016 1.016)
					(thickness 0.1524)
				)
			)
		)
		(duplicate_pad_numbers_are_jumpers no)
		(fp_line
			(start 0.508 0)
			(end -0.508 0)
			(stroke
				(width 0.2032)
				(type default)
			)
			(layer "F.SilkS")
		)
		(fp_rect
			(start -0.5842 1.3335)
			(end 0.5842 -1.3335)
			(stroke
				(width 0)
				(type default)
			)
			(fill no)
			(layer "F.CrtYd")
		)
		(fp_rect
			(start -0.5842 1.3335)
			(end 0.5842 -1.3335)
			(stroke
				(width 0)
				(type default)
			)
			(fill no)
			(layer "F.Fab")
		)
		(pad "1" smd custom
			(at 0 -0.762 180)
			(size 0.2159 0.2159)
			(layers "F.Cu" "F.Mask" "F.Paste")
			(net "P12V_HDD14")
			(options
				(clearance outline)
				(anchor circle)
			)
			(primitives
				(gr_poly
					(pts
						(arc
							(start -0.3302 -0.4318)
							(mid -0.402042 -0.402042)
							(end -0.4318 -0.3302)
						)
						(arc
							(start -0.4318 0.3302)
							(mid -0.402042 0.402042)
							(end -0.3302 0.4318)
						)
						(arc
							(start 0.3302 0.4318)
							(mid 0.402042 0.402042)
							(end 0.4318 0.3302)
						)
						(arc
							(start 0.4318 -0.3302)
							(mid 0.402042 -0.402042)
							(end 0.3302 -0.4318)
						)
					)
					(width 0)
					(fill yes)
				)
			)
		)
		(pad "2" smd custom
			(at 0 0.762 180)
			(size 0.2159 0.2159)
			(layers "F.Cu" "F.Mask" "F.Paste")
			(net "GND")
			(options
				(clearance outline)
				(anchor circle)
			)
			(primitives
				(gr_poly
					(pts
						(arc
							(start -0.3302 -0.4318)
							(mid -0.402042 -0.402042)
							(end -0.4318 -0.3302)
						)
						(arc
							(start -0.4318 0.3302)
							(mid -0.402042 0.402042)
							(end -0.3302 0.4318)
						)
						(arc
							(start 0.3302 0.4318)
							(mid 0.402042 0.402042)
							(end 0.4318 0.3302)
						)
						(arc
							(start 0.4318 -0.3302)
							(mid 0.402042 -0.402042)
							(end 0.3302 -0.4318)
						)
					)
					(width 0)
					(fill yes)
				)
			)
		)
	)
)
